(kicad_pcb
	(version 20260206)
	(generator "pcbnew")
	(generator_version "10.0")
	(general
		(thickness 1.6)
		(legacy_teardrops no)
	)
	(paper "A4")
	(title_block
		(title "peb — Lightning_PEB_BRD.brd")
		(comment 1 "Lightning (Wiwynn / Facebook NVMe JBOF) / footprints 976-980 of 2563")
	)
	(layers
		(0 "F.Cu" signal "TOP")
		(4 "In1.Cu" signal "L2GND")
		(6 "In2.Cu" signal "L3")
		(8 "In3.Cu" signal "L4VCC")
		(10 "In4.Cu" signal "L5VCC")
		(12 "In5.Cu" signal "L6")
		(14 "In6.Cu" signal "L7GND")
		(2 "B.Cu" signal "BOTTOM")
		(9 "F.Adhes" user "F.Adhesive")
		(11 "B.Adhes" user "B.Adhesive")
		(13 "F.Paste" user "Package Geometry/Pastemask Top")
		(15 "B.Paste" user "Package Geometry/Pastemask Bottom")
		(5 "F.SilkS" user "Ref Des/Silkscreen Top")
		(7 "B.SilkS" user "Ref Des/Silkscreen Bottom")
		(1 "F.Mask" user "Board Geometry/Soldermask Top")
		(3 "B.Mask" user "Board Geometry/Soldermask Bottom")
		(17 "Dwgs.User" user "User.Drawings")
		(19 "Cmts.User" user "User.Comments")
		(21 "Eco1.User" user "User.Eco1")
		(23 "Eco2.User" user "User.Eco2")
		(25 "Edge.Cuts" user "Board Geometry/Outline")
		(27 "Margin" user)
		(31 "F.CrtYd" user "Package Geometry/Place Bound Top")
		(29 "B.CrtYd" user "Package Geometry/Place Bound Bottom")
		(35 "F.Fab" user "Ref Des/Assembly Top")
		(33 "B.Fab" user "Ref Des/Assembly Bottom")
	)
	(footprint ""
		(layer "F.Cu")
		(at 215.876124 -203.047092 180)
		(property "Reference" "C3215"
			(at 0 0 180)
			(layer "F.SilkS")
			(hide yes)
			(effects
				(font
					(size 1.27 1.27)
				)
			)
		)
		(property "Value" "SCD1U25V2KX-2-GP"
			(at 1.1811 -2.7051 180)
			(unlocked yes)
			(layer "F.Fab")
			(hide yes)
			(effects
				(font
					(size 1.016 1.016)
					(thickness 0.1524)
				)
			)
		)
		(property "Device Type" "C402H22"
			(at 1.1811 -4.2291 180)
			(unlocked yes)
			(layer "F.Fab")
			(hide yes)
			(effects
				(font
					(size 1.016 1.016)
					(thickness 0.1524)
				)
			)
		)
		(duplicate_pad_numbers_are_jumpers no)
		(fp_rect
			(start -0.4318 0.9525)
			(end 0.4318 -0.9525)
			(stroke
				(width 0)
				(type default)
			)
			(fill no)
			(layer "F.CrtYd")
		)
		(fp_rect
			(start -0.4318 0.9525)
			(end 0.4318 -0.9525)
			(stroke
				(width 0)
				(type default)
			)
			(fill no)
			(layer "F.Fab")
		)
		(pad "1" smd custom
			(at 0 -0.4445 180)
			(size 0.1524 0.1524)
			(layers "F.Cu" "F.Mask" "F.Paste")
			(net "P3V3_STBY")
			(options
				(clearance outline)
				(anchor circle)
			)
			(primitives
				(gr_poly
					(pts
						(arc
							(start 0.3048 -0.2032)
							(mid 0.275042 -0.275042)
							(end 0.2032 -0.3048)
						)
						(arc
							(start -0.2032 -0.3048)
							(mid -0.275042 -0.275042)
							(end -0.3048 -0.2032)
						)
						(arc
							(start -0.3048 0.2032)
							(mid -0.275042 0.275042)
							(end -0.2032 0.3048)
						)
						(arc
							(start 0.2032 0.3048)
							(mid 0.275042 0.275042)
							(end 0.3048 0.2032)
						)
					)
					(width 0)
					(fill yes)
				)
			)
		)
		(pad "2" smd custom
			(at 0 0.4445 180)
			(size 0.1524 0.1524)
			(layers "F.Cu" "F.Mask" "F.Paste")
			(net "GND")
			(options
				(clearance outline)
				(anchor circle)
			)
			(primitives
				(gr_poly
					(pts
						(arc
							(start 0.3048 -0.2032)
							(mid 0.275042 -0.275042)
							(end 0.2032 -0.3048)
						)
						(arc
							(start -0.2032 -0.3048)
							(mid -0.275042 -0.275042)
							(end -0.3048 -0.2032)
						)
						(arc
							(start -0.3048 0.2032)
							(mid -0.275042 0.275042)
							(end -0.2032 0.3048)
						)
						(arc
							(start 0.2032 0.3048)
							(mid 0.275042 0.275042)
							(end 0.3048 0.2032)
						)
					)
					(width 0)
					(fill yes)
				)
			)
		)
	)
	(footprint ""
		(layer "F.Cu")
		(at 194.8688 -30.7848 -90)
		(property "Reference" "R800"
			(at 0 0 270)
			(layer "F.SilkS")
			(hide yes)
			(effects
				(font
					(size 1.27 1.27)
				)
			)
		)
		(property "Value" "4K7R2F-GP"
			(at 0.064008 -3.993896 270)
			(unlocked yes)
			(layer "F.Fab")
			(hide yes)
			(effects
				(font
					(size 1.016 1.016)
					(thickness 0.1524)
				)
			)
		)
		(property "Device Type" "R402H16"
			(at 0.064008 -5.517896 270)
			(unlocked yes)
			(layer "F.Fab")
			(hide yes)
			(effects
				(font
					(size 1.016 1.016)
					(thickness 0.1524)
				)
			)
		)
		(duplicate_pad_numbers_are_jumpers no)
		(fp_line
			(start -0.508 -0.9398)
			(end -0.508 0.9398)
			(stroke
				(width 0.1524)
				(type default)
			)
			(layer "F.SilkS")
		)
		(fp_line
			(start 0.508 -0.9398)
			(end -0.508 -0.9398)
			(stroke
				(width 0.1524)
				(type default)
			)
			(layer "F.SilkS")
		)
		(fp_rect
			(start -0.508 0.9398)
			(end 0.508 -0.9398)
			(stroke
				(width 0)
				(type default)
			)
			(fill no)
			(layer "F.CrtYd")
		)
		(fp_rect
			(start -0.508 0.9398)
			(end 0.508 -0.9398)
			(stroke
				(width 0)
				(type default)
			)
			(fill no)
			(layer "F.Fab")
		)
		(pad "1" smd custom
			(at 0 -0.4445 270)
			(size 0.1397 0.1397)
			(layers "F.Cu" "F.Mask" "F.Paste")
			(net "U55_A2")
			(options
				(clearance outline)
				(anchor circle)
			)
			(primitives
				(gr_poly
					(pts
						(arc
							(start -0.1778 -0.2794)
							(mid -0.249642 -0.249642)
							(end -0.2794 -0.1778)
						)
						(arc
							(start -0.2794 0.1778)
							(mid -0.249642 0.249642)
							(end -0.1778 0.2794)
						)
						(arc
							(start 0.1778 0.2794)
							(mid 0.249642 0.249642)
							(end 0.2794 0.1778)
						)
						(arc
							(start 0.2794 -0.1778)
							(mid 0.249642 -0.249642)
							(end 0.1778 -0.2794)
						)
					)
					(width 0)
					(fill yes)
				)
			)
		)
		(pad "2" smd custom
			(at 0 0.4445 270)
			(size 0.1397 0.1397)
			(layers "F.Cu" "F.Mask" "F.Paste")
			(net "P3V3_STBY")
			(options
				(clearance outline)
				(anchor circle)
			)
			(primitives
				(gr_poly
					(pts
						(arc
							(start -0.1778 -0.2794)
							(mid -0.249642 -0.249642)
							(end -0.2794 -0.1778)
						)
						(arc
							(start -0.2794 0.1778)
							(mid -0.249642 0.249642)
							(end -0.1778 0.2794)
						)
						(arc
							(start 0.1778 0.2794)
							(mid 0.249642 0.249642)
							(end 0.2794 0.1778)
						)
						(arc
							(start 0.2794 -0.1778)
							(mid 0.249642 -0.249642)
							(end 0.1778 -0.2794)
						)
					)
					(width 0)
					(fill yes)
				)
			)
		)
	)
	(footprint ""
		(layer "F.Cu")
		(at 160.782 -90.5764 90)
		(property "Reference" "U196"
			(at 0 0 90)
			(layer "F.SilkS")
			(hide yes)
			(effects
				(font
					(size 1.27 1.27)
				)
			)
		)
		(property "Value" "9FGV0431AKLFT-GP"
			(at -5.4229 -4.6482 90)
			(unlocked yes)
			(layer "F.Fab")
			(hide yes)
			(effects
				(font
					(size 1.016 1.016)
					(thickness 0.1524)
				)
			)
		)
		(property "Device Type" "QFN32-G3D3H40"
			(at -5.4229 -6.1722 90)
			(unlocked yes)
			(layer "F.Fab")
			(hide yes)
			(effects
				(font
					(size 1.016 1.016)
					(thickness 0.1524)
				)
			)
		)
		(duplicate_pad_numbers_are_jumpers no)
		(fp_line
			(start -2.2479 -3.5179)
			(end -3.5179 -3.5179)
			(stroke
				(width 0.1524)
				(type default)
			)
			(layer "F.SilkS")
		)
		(fp_line
			(start -3.5179 -3.5179)
			(end -3.5179 -2.2479)
			(stroke
				(width 0.1524)
				(type default)
			)
			(layer "F.SilkS")
		)
		(fp_line
			(start -0.249936 -3.160522)
			(end -0.249936 -3.668522)
			(stroke
				(width 0.1524)
				(type default)
			)
			(layer "F.SilkS")
		)
		(fp_line
			(start -3.160522 -1.249934)
			(end -3.922522 -1.249934)
			(stroke
				(width 0.1524)
				(type default)
			)
			(layer "F.SilkS")
		)
		(fp_line
			(start 3.160522 -0.750062)
			(end 3.922522 -0.750062)
			(stroke
				(width 0.1524)
				(type default)
			)
			(layer "F.SilkS")
		)
		(fp_line
			(start -3.160522 1.249934)
			(end -3.668522 1.249934)
			(stroke
				(width 0.1524)
				(type default)
			)
			(layer "F.SilkS")
		)
		(fp_line
			(start 3.160522 1.75006)
			(end 3.668522 1.75006)
			(stroke
				(width 0.1524)
				(type default)
			)
			(layer "F.SilkS")
		)
		(fp_line
			(start -3.5179 2.2479)
			(end -3.5179 3.5179)
			(stroke
				(width 0.1524)
				(type default)
			)
			(layer "F.SilkS")
		)
		(fp_line
			(start -0.249936 3.160522)
			(end -0.249936 3.922522)
			(stroke
				(width 0.1524)
				(type default)
			)
			(layer "F.SilkS")
		)
		(fp_line
			(start 3.5179 3.5179)
			(end 3.5179 2.2479)
			(stroke
				(width 0.1524)
				(type default)
			)
			(layer "F.SilkS")
		)
		(fp_line
			(start 2.2479 3.5179)
			(end 3.5179 3.5179)
			(stroke
				(width 0.1524)
				(type default)
			)
			(layer "F.SilkS")
		)
		(fp_line
			(start -3.5179 3.5179)
			(end -2.2479 3.5179)
			(stroke
				(width 0.1524)
				(type default)
			)
			(layer "F.SilkS")
		)
		(fp_poly
			(pts
				(xy 3.5179 -3.5179) (xy 2.2479 -3.5179) (xy 3.5179 -2.2479)
			)
			(stroke
				(width 0)
				(type default)
			)
			(fill yes)
			(layer "F.SilkS")
		)
		(fp_rect
			(start -2.5019 2.5019)
			(end 2.5019 -2.5019)
			(stroke
				(width 0)
				(type default)
			)
			(fill no)
			(layer "F.CrtYd")
		)
		(fp_poly
			(pts
				(xy -3.5179 3.5179) (xy -3.5179 -3.5179) (xy 3.5179 -3.5179) (xy 3.5179 -0.8763) (xy 2.5019 -0.8763)
				(xy 2.5019 -2.5019) (xy -2.5019 -2.5019) (xy -2.5019 2.5019) (xy 2.5019 2.5019) (xy 2.5019 -0.8636)
				(xy 3.5179 -0.8636) (xy 3.5179 3.5179)
			)
			(stroke
				(width 0)
				(type default)
			)
			(fill no)
			(layer "F.CrtYd")
		)
		(fp_rect
			(start -3.5179 3.5179)
			(end 3.5179 -3.5179)
			(stroke
				(width 0)
				(type default)
			)
			(fill no)
			(layer "F.Fab")
		)
		(pad "1" smd rect
			(at 1.75006 -2.538222 90)
			(size 0.3048 0.9398)
			(layers "F.Cu" "F.Mask" "F.Paste")
			(net "GND")
		)
		(pad "2" smd rect
			(at 1.249934 -2.487422 90)
			(size 0.3048 1.0414)
			(layers "F.Cu" "F.Mask" "F.Paste")
			(net "XTAL_X1")
		)
		(pad "3" smd rect
			(at 0.750062 -2.487422 90)
			(size 0.3048 1.0414)
			(layers "F.Cu" "F.Mask" "F.Paste")
			(net "XTAL_X2_CLKGEN")
		)
		(pad "4" smd rect
			(at 0.249936 -2.487422 90)
			(size 0.3048 1.0414)
			(layers "F.Cu" "F.Mask" "F.Paste")
			(net "P1V8_CLKGEN")
		)
		(pad "5" smd rect
			(at -0.249936 -2.487422 90)
			(size 0.3048 1.0414)
			(layers "F.Cu" "F.Mask" "F.Paste")
			(net "P1V8_CLKGEN")
		)
		(pad "6" smd rect
			(at -0.750062 -2.487422 90)
			(size 0.3048 1.0414)
			(layers "F.Cu" "F.Mask" "F.Paste")
			(net "CLKGNE_SADR")
		)
		(pad "7" smd rect
			(at -1.249934 -2.487422 90)
			(size 0.3048 1.0414)
			(layers "F.Cu" "F.Mask" "F.Paste")
			(net "GND")
		)
		(pad "8" smd rect
			(at -1.75006 -2.538222 90)
			(size 0.3048 0.9398)
			(layers "F.Cu" "F.Mask" "F.Paste")
			(net "GND")
		)
		(pad "9" smd rect
			(at -2.538222 -1.75006 90)
			(size 0.9398 0.3048)
			(layers "F.Cu" "F.Mask" "F.Paste")
			(net "P1V8_CLKGEN")
		)
		(pad "10" smd rect
			(at -2.487422 -1.249934 90)
			(size 1.0414 0.3048)
			(layers "F.Cu" "F.Mask" "F.Paste")
			(net "CLKGEN_SCL")
		)
		(pad "11" smd rect
			(at -2.487422 -0.750062 90)
			(size 1.0414 0.3048)
			(layers "F.Cu" "F.Mask" "F.Paste")
			(net "CLKGEN_SDA")
		)
		(pad "12" smd rect
			(at -2.487422 -0.249936 90)
			(size 1.0414 0.3048)
			(layers "F.Cu" "F.Mask" "F.Paste")
			(net "PCIE_CLKGEN2_OE0_R")
		)
		(pad "13" smd rect
			(at -2.487422 0.249936 90)
			(size 1.0414 0.3048)
			(layers "F.Cu" "F.Mask" "F.Paste")
			(net "PCIE_REFCLK_D_P_R")
		)
		(pad "14" smd rect
			(at -2.487422 0.750062 90)
			(size 1.0414 0.3048)
			(layers "F.Cu" "F.Mask" "F.Paste")
			(net "PCIE_REFCLK_D_N_R")
		)
		(pad "15" smd rect
			(at -2.487422 1.249934 90)
			(size 1.0414 0.3048)
			(layers "F.Cu" "F.Mask" "F.Paste")
			(net "GND")
		)
		(pad "16" smd rect
			(at -2.538222 1.75006 90)
			(size 0.9398 0.3048)
			(layers "F.Cu" "F.Mask" "F.Paste")
			(net "P1V8_CLKGEN")
		)
		(pad "17" smd rect
			(at -1.75006 2.538222 90)
			(size 0.3048 0.9398)
			(layers "F.Cu" "F.Mask" "F.Paste")
			(net "CLKGEN_OE1_R")
		)
		(pad "18" smd rect
			(at -1.249934 2.487422 90)
			(size 0.3048 1.0414)
			(layers "F.Cu" "F.Mask" "F.Paste")
			(net "CLKGEN_P1_R")
		)
		(pad "19" smd rect
			(at -0.750062 2.487422 90)
			(size 0.3048 1.0414)
			(layers "F.Cu" "F.Mask" "F.Paste")
			(net "CLKGEN_N1_R")
		)
		(pad "20" smd rect
			(at -0.249936 2.487422 90)
			(size 0.3048 1.0414)
			(layers "F.Cu" "F.Mask" "F.Paste")
			(net "GND")
		)
		(pad "21" smd rect
			(at 0.249936 2.487422 90)
			(size 0.3048 1.0414)
			(layers "F.Cu" "F.Mask" "F.Paste")
			(net "P1V8_CLKGEN_A")
		)
		(pad "22" smd rect
			(at 0.750062 2.487422 90)
			(size 0.3048 1.0414)
			(layers "F.Cu" "F.Mask" "F.Paste")
			(net "CLKGEN_P2_R")
		)
		(pad "23" smd rect
			(at 1.249934 2.487422 90)
			(size 0.3048 1.0414)
			(layers "F.Cu" "F.Mask" "F.Paste")
			(net "CLKGEN_N2_R")
		)
		(pad "24" smd rect
			(at 1.75006 2.538222 90)
			(size 0.3048 0.9398)
			(layers "F.Cu" "F.Mask" "F.Paste")
			(net "CLKGEN_OE2_R")
		)
		(pad "25" smd rect
			(at 2.538222 1.75006 90)
			(size 0.9398 0.3048)
			(layers "F.Cu" "F.Mask" "F.Paste")
			(net "P1V8_CLKGEN")
		)
		(pad "26" smd rect
			(at 2.487422 1.249934 90)
			(size 1.0414 0.3048)
			(layers "F.Cu" "F.Mask" "F.Paste")
			(net "GND")
		)
		(pad "27" smd rect
			(at 2.487422 0.750062 90)
			(size 1.0414 0.3048)
			(layers "F.Cu" "F.Mask" "F.Paste")
			(net "CLKGEN_P3_R")
		)
		(pad "28" smd rect
			(at 2.487422 0.249936 90)
			(size 1.0414 0.3048)
			(layers "F.Cu" "F.Mask" "F.Paste")
			(net "CLKGEN_N3_R")
		)
		(pad "29" smd rect
			(at 2.487422 -0.249936 90)
			(size 1.0414 0.3048)
			(layers "F.Cu" "F.Mask" "F.Paste")
			(net "CLKGEN_OE3_R")
		)
		(pad "30" smd rect
			(at 2.487422 -0.750062 90)
			(size 1.0414 0.3048)
			(layers "F.Cu" "F.Mask" "F.Paste")
			(net "GND")
		)
		(pad "31" smd rect
			(at 2.487422 -1.249934 90)
			(size 1.0414 0.3048)
			(layers "F.Cu" "F.Mask" "F.Paste")
			(net "CLKGEN_PWGD")
		)
		(pad "32" smd rect
			(at 2.538222 -1.75006 90)
			(size 0.9398 0.3048)
			(layers "F.Cu" "F.Mask" "F.Paste")
			(net "CLKGNE_SS_EN")
		)
		(pad "33" smd rect
			(at 0 0 90)
			(size 3.302 3.302)
			(layers "F.Cu" "F.Mask" "F.Paste")
			(net "GND")
		)
	)
	(footprint ""
		(layer "F.Cu")
		(at 122.4788 -99.8982 -90)
		(property "Reference" "R427"
			(at 0 0 270)
			(layer "F.SilkS")
			(hide yes)
			(effects
				(font
					(size 1.27 1.27)
				)
			)
		)
		(property "Value" "2KR2F-3-GP"
			(at 0.064008 -3.993896 270)
			(unlocked yes)
			(layer "F.Fab")
			(hide yes)
			(effects
				(font
					(size 1.016 1.016)
					(thickness 0.1524)
				)
			)
		)
		(property "Device Type" "R402H16"
			(at 0.064008 -5.517896 270)
			(unlocked yes)
			(layer "F.Fab")
			(hide yes)
			(effects
				(font
					(size 1.016 1.016)
					(thickness 0.1524)
				)
			)
		)
		(duplicate_pad_numbers_are_jumpers no)
		(fp_line
			(start -0.508 -0.9398)
			(end -0.508 0.9398)
			(stroke
				(width 0.1524)
				(type default)
			)
			(layer "F.SilkS")
		)
		(fp_line
			(start 0.508 -0.9398)
			(end -0.508 -0.9398)
			(stroke
				(width 0.1524)
				(type default)
			)
			(layer "F.SilkS")
		)
		(fp_rect
			(start -0.508 0.9398)
			(end 0.508 -0.9398)
			(stroke
				(width 0)
				(type default)
			)
			(fill no)
			(layer "F.CrtYd")
		)
		(fp_rect
			(start -0.508 0.9398)
			(end 0.508 -0.9398)
			(stroke
				(width 0)
				(type default)
			)
			(fill no)
			(layer "F.Fab")
		)
		(pad "1" smd custom
			(at 0 -0.4445 270)
			(size 0.1397 0.1397)
			(layers "F.Cu" "F.Mask" "F.Paste")
			(net "P3V3_STBY")
			(options
				(clearance outline)
				(anchor circle)
			)
			(primitives
				(gr_poly
					(pts
						(arc
							(start -0.1778 -0.2794)
							(mid -0.249642 -0.249642)
							(end -0.2794 -0.1778)
						)
						(arc
							(start -0.2794 0.1778)
							(mid -0.249642 0.249642)
							(end -0.1778 0.2794)
						)
						(arc
							(start 0.1778 0.2794)
							(mid 0.249642 0.249642)
							(end 0.2794 0.1778)
						)
						(arc
							(start 0.2794 -0.1778)
							(mid 0.249642 -0.249642)
							(end 0.1778 -0.2794)
						)
					)
					(width 0)
					(fill yes)
				)
			)
		)
		(pad "2" smd custom
			(at 0 0.4445 270)
			(size 0.1397 0.1397)
			(layers "F.Cu" "F.Mask" "F.Paste")
			(net "BUF_I2C_SCL_2_R")
			(options
				(clearance outline)
				(anchor circle)
			)
			(primitives
				(gr_poly
					(pts
						(arc
							(start -0.1778 -0.2794)
							(mid -0.249642 -0.249642)
							(end -0.2794 -0.1778)
						)
						(arc
							(start -0.2794 0.1778)
							(mid -0.249642 0.249642)
							(end -0.1778 0.2794)
						)
						(arc
							(start 0.1778 0.2794)
							(mid 0.249642 0.249642)
							(end 0.2794 0.1778)
						)
						(arc
							(start 0.2794 -0.1778)
							(mid 0.249642 -0.249642)
							(end 0.1778 -0.2794)
						)
					)
					(width 0)
					(fill yes)
				)
			)
		)
	)
	(footprint ""
		(layer "F.Cu")
		(at 217.043 -12.065)
		(property "Reference" "SC1115"
			(at 0 0 0)
			(layer "F.SilkS")
			(hide yes)
			(effects
				(font
					(size 1.27 1.27)
				)
			)
		)
		(property "Value" "SCD1U16V2KX-3GP"
			(at 1.1811 -2.7051 0)
			(unlocked yes)
			(layer "F.Fab")
			(hide yes)
			(effects
				(font
					(size 1.016 1.016)
					(thickness 0.1524)
				)
			)
		)
		(property "Device Type" "C402H22"
			(at 1.1811 -4.2291 0)
			(unlocked yes)
			(layer "F.Fab")
			(hide yes)
			(effects
				(font
					(size 1.016 1.016)
					(thickness 0.1524)
				)
			)
		)
		(duplicate_pad_numbers_are_jumpers no)
		(fp_rect
			(start -0.4318 0.9525)
			(end 0.4318 -0.9525)
			(stroke
				(width 0)
				(type default)
			)
			(fill no)
			(layer "F.CrtYd")
		)
		(fp_rect
			(start -0.4318 0.9525)
			(end 0.4318 -0.9525)
			(stroke
				(width 0)
				(type default)
			)
			(fill no)
			(layer "F.Fab")
		)
		(pad "1" smd custom
			(at 0 -0.4445)
			(size 0.1524 0.1524)
			(layers "F.Cu" "F.Mask" "F.Paste")
			(net "DUT_VDDO")
			(options
				(clearance outline)
				(anchor circle)
			)
			(primitives
				(gr_poly
					(pts
						(arc
							(start 0.3048 -0.2032)
							(mid 0.275042 -0.275042)
							(end 0.2032 -0.3048)
						)
						(arc
							(start -0.2032 -0.3048)
							(mid -0.275042 -0.275042)
							(end -0.3048 -0.2032)
						)
						(arc
							(start -0.3048 0.2032)
							(mid -0.275042 0.275042)
							(end -0.2032 0.3048)
						)
						(arc
							(start 0.2032 0.3048)
							(mid 0.275042 0.275042)
							(end 0.3048 0.2032)
						)
					)
					(width 0)
					(fill yes)
				)
			)
		)
		(pad "2" smd custom
			(at 0 0.4445)
			(size 0.1524 0.1524)
			(layers "F.Cu" "F.Mask" "F.Paste")
			(net "GND")
			(options
				(clearance outline)
				(anchor circle)
			)
			(primitives
				(gr_poly
					(pts
						(arc
							(start 0.3048 -0.2032)
							(mid 0.275042 -0.275042)
							(end 0.2032 -0.3048)
						)
						(arc
							(start -0.2032 -0.3048)
							(mid -0.275042 -0.275042)
							(end -0.3048 -0.2032)
						)
						(arc
							(start -0.3048 0.2032)
							(mid -0.275042 0.275042)
							(end -0.2032 0.3048)
						)
						(arc
							(start 0.2032 0.3048)
							(mid 0.275042 0.275042)
							(end 0.3048 0.2032)
						)
					)
					(width 0)
					(fill yes)
				)
			)
		)
	)
)
